# SCM (Grand Teton) — schematic netlist excerpt (pin names and nets, part order shuffled) for the footprints in the layout excerpt that follows; sources: Cadence DE-HDL packaged netlist, KiCad conversion of 12092022_DA0F0TMDCD0_F0T_Management_Board_D_brd_V3_OCP.brd

U57  74LVC1G07GW  IC  pkg SOT353_Q  page 50
  NC  = NC_U57_P1
  A  = REAR_AC_PWR_BMC_BTN_N
  GND  = GND
  Y  = AC_PWR_BMC_BTN_N
  VCC  = P3V3_AUX

R854  Q_RES  4.7K 1% EMPTY  pkg 0402LF  page 14 : A = P1V8_AUX ; B = FM_BOARD_BMC_REV_ID2

(kicad_pcb
	(version 20260206)
	(generator "pcbnew")
	(generator_version "10.0")
	(general
		(thickness 1.6)
		(legacy_teardrops no)
	)
	(paper "A4")
	(title_block
		(title "12092022_DA0F0TMDCD0_F0T_Management_Board_D_brd_V3_OCP.brd")
		(comment 1 "Grand Teton / footprints 651-652 of 1440")
	)
	(layers
		(0 "F.Cu" signal "TOP")
		(4 "In1.Cu" signal "GND")
		(6 "In2.Cu" signal "IN1")
		(8 "In3.Cu" signal "GND1")
		(10 "In4.Cu" signal "IN2")
		(12 "In5.Cu" signal "VCC")
		(14 "In6.Cu" signal "VCC1")
		(16 "In7.Cu" signal "IN3")
		(18 "In8.Cu" signal "GND2")
		(20 "In9.Cu" signal "IN4")
		(22 "In10.Cu" signal "GND3")
		(2 "B.Cu" signal "BOTTOM")
		(9 "F.Adhes" user "F.Adhesive")
		(11 "B.Adhes" user "B.Adhesive")
		(13 "F.Paste" user "Package Geometry/Pastemask Top")
		(15 "B.Paste" user "Package Geometry/Pastemask Bottom")
		(5 "F.SilkS" user "Ref Des/Silkscreen Top")
		(7 "B.SilkS" user "Ref Des/Silkscreen Bottom")
		(1 "F.Mask" user "Board Geometry/Soldermask Top")
		(3 "B.Mask" user "Board Geometry/Soldermask Bottom")
		(17 "Dwgs.User" user "User.Drawings")
		(19 "Cmts.User" user "User.Comments")
		(21 "Eco1.User" user "User.Eco1")
		(23 "Eco2.User" user "User.Eco2")
		(25 "Edge.Cuts" user "Board Geometry/Outline")
		(27 "Margin" user)
		(31 "F.CrtYd" user "Package Geometry/Place Bound Top")
		(29 "B.CrtYd" user "Package Geometry/Place Bound Bottom")
		(35 "F.Fab" user "Ref Des/Assembly Top")
		(33 "B.Fab" user "Ref Des/Assembly Bottom")
	)
	(footprint ""
		(layer "F.Cu")
		(at 68.072 -11.43)
		(property "Reference" "U57"
			(at -0.463042 -1.674876 0)
			(unlocked yes)
			(layer "F.SilkS")
			(effects
				(font
					(size 0.7874 0.5842)
					(thickness 0.1524)
				)
				(justify left)
			)
		)
		(property "Value" ""
			(at 0 0 0)
			(layer "F.Fab")
			(effects
				(font
					(size 1.27 1.27)
				)
			)
		)
		(duplicate_pad_numbers_are_jumpers no)
		(fp_line
			(start -1.4986 -1.100074)
			(end 1.4986 -1.100074)
			(stroke
				(width 0.1524)
				(type default)
			)
			(layer "F.SilkS")
		)
		(fp_line
			(start -1.4986 1.100074)
			(end -1.4986 -1.100074)
			(stroke
				(width 0.1524)
				(type default)
			)
			(layer "F.SilkS")
		)
		(fp_line
			(start 1.4986 -1.100074)
			(end 1.4986 1.100074)
			(stroke
				(width 0.1524)
				(type default)
			)
			(layer "F.SilkS")
		)
		(fp_line
			(start 1.4986 1.100074)
			(end -1.4986 1.100074)
			(stroke
				(width 0.1524)
				(type default)
			)
			(layer "F.SilkS")
		)
		(fp_poly
			(pts
				(xy -2.20472 -0.338328) (xy -2.20472 -0.963168) (xy -1.651 -0.635)
			)
			(stroke
				(width 0)
				(type default)
			)
			(fill yes)
			(layer "F.SilkS")
		)
		(fp_line
			(start -0.67437 -1.100074)
			(end 0.67437 -1.100074)
			(stroke
				(width 0.1)
				(type default)
			)
			(layer "F.Fab")
		)
		(fp_line
			(start -0.67437 1.100074)
			(end -0.67437 -1.100074)
			(stroke
				(width 0.1)
				(type default)
			)
			(layer "F.Fab")
		)
		(fp_line
			(start 0.67437 -1.100074)
			(end 0.67437 1.100074)
			(stroke
				(width 0.1)
				(type default)
			)
			(layer "F.Fab")
		)
		(fp_line
			(start 0.67437 1.100074)
			(end -0.67437 1.100074)
			(stroke
				(width 0.1)
				(type default)
			)
			(layer "F.Fab")
		)
		(fp_poly
			(pts
				(xy -2.20472 -0.338328) (xy -2.20472 -0.963168) (xy -1.651 -0.635)
			)
			(stroke
				(width 0)
				(type default)
			)
			(fill yes)
			(layer "F.Fab")
		)
		(pad "1" smd rect
			(at -0.889 -0.649986)
			(size 1.016 0.381)
			(layers "F.Cu" "F.Mask" "F.Paste")
			(net "NC_U57_P1")
		)
		(pad "2" smd rect
			(at -0.889 0)
			(size 1.016 0.381)
			(layers "F.Cu" "F.Mask" "F.Paste")
			(net "REAR_AC_PWR_BMC_BTN_N")
		)
		(pad "3" smd rect
			(at -0.889 0.649986)
			(size 1.016 0.381)
			(layers "F.Cu" "F.Mask" "F.Paste")
			(net "GND")
		)
		(pad "4" smd rect
			(at 0.889 0.649986)
			(size 1.016 0.381)
			(layers "F.Cu" "F.Mask" "F.Paste")
			(net "AC_PWR_BMC_BTN_N")
		)
		(pad "5" smd rect
			(at 0.889 -0.649986)
			(size 1.016 0.381)
			(layers "F.Cu" "F.Mask" "F.Paste")
			(net "P3V3_AUX")
		)
	)
	(footprint ""
		(layer "F.Cu")
		(at 72.39 -19.685 90)
		(property "Reference" "R854"
			(at 0 0 90)
			(layer "F.SilkS")
			(hide yes)
			(effects
				(font
					(size 1.27 1.27)
				)
			)
		)
		(property "Value" ""
			(at 0 0 90)
			(layer "F.Fab")
			(effects
				(font
					(size 1.27 1.27)
				)
			)
		)
		(duplicate_pad_numbers_are_jumpers no)
		(fp_line
			(start 0.7874 -0.4064)
			(end 0.7874 0.4064)
			(stroke
				(width 0.1524)
				(type default)
			)
			(layer "F.SilkS")
		)
		(fp_line
			(start -0.7874 -0.4064)
			(end 0.7874 -0.4064)
			(stroke
				(width 0.1524)
				(type default)
			)
			(layer "F.SilkS")
		)
		(fp_line
			(start 0.7874 0.4064)
			(end -0.7874 0.4064)
			(stroke
				(width 0.1524)
				(type default)
			)
			(layer "F.SilkS")
		)
		(fp_line
			(start -0.7874 0.4064)
			(end -0.7874 -0.4064)
			(stroke
				(width 0.1524)
				(type default)
			)
			(layer "F.SilkS")
		)
		(fp_line
			(start -0.12065 -0.305054)
			(end -0.12065 -0.2794)
			(stroke
				(width 0.1)
				(type default)
			)
			(layer "F.Fab")
		)
		(fp_line
			(start -0.67945 -0.305054)
			(end -0.12065 -0.305054)
			(stroke
				(width 0.1)
				(type default)
			)
			(layer "F.Fab")
		)
		(fp_line
			(start 0.67945 -0.3048)
			(end 0.67945 0.3048)
			(stroke
				(width 0.1)
				(type default)
			)
			(layer "F.Fab")
		)
		(fp_line
			(start 0.12065 -0.3048)
			(end 0.67945 -0.3048)
			(stroke
				(width 0.1)
				(type default)
			)
			(layer "F.Fab")
		)
		(fp_line
			(start 0.12065 -0.2794)
			(end 0.12065 -0.3048)
			(stroke
				(width 0.1)
				(type default)
			)
			(layer "F.Fab")
		)
		(fp_line
			(start -0.12065 -0.2794)
			(end 0.12065 -0.2794)
			(stroke
				(width 0.1)
				(type default)
			)
			(layer "F.Fab")
		)
		(fp_line
			(start 0.120396 0.2794)
			(end -0.12065 0.2794)
			(stroke
				(width 0.1)
				(type default)
			)
			(layer "F.Fab")
		)
		(fp_line
			(start -0.12065 0.2794)
			(end -0.12065 0.3048)
			(stroke
				(width 0.1)
				(type default)
			)
			(layer "F.Fab")
		)
		(fp_line
			(start 0.67945 0.3048)
			(end 0.120396 0.3048)
			(stroke
				(width 0.1)
				(type default)
			)
			(layer "F.Fab")
		)
		(fp_line
			(start 0.120396 0.3048)
			(end 0.120396 0.2794)
			(stroke
				(width 0.1)
				(type default)
			)
			(layer "F.Fab")
		)
		(fp_line
			(start -0.12065 0.3048)
			(end -0.67945 0.3048)
			(stroke
				(width 0.1)
				(type default)
			)
			(layer "F.Fab")
		)
		(fp_line
			(start -0.67945 0.3048)
			(end -0.67945 -0.305054)
			(stroke
				(width 0.1)
				(type default)
			)
			(layer "F.Fab")
		)
		(pad "1" smd circle
			(at -0.40005 0 90)
			(size 0 0)
			(layers "F.Cu" "F.Mask" "F.Paste")
			(net "P1V8_AUX")
		)
		(pad "2" smd circle
			(at 0.40005 0 90)
			(size 0 0)
			(layers "F.Cu" "F.Mask" "F.Paste")
			(net "FM_BOARD_BMC_REV_ID2")
		)
	)
)
